(kicad_pcb
	(version 20260206)
	(generator "pcbnew")
	(generator_version "10.0")
	(general
		(thickness 1.6)
		(legacy_teardrops no)
	)
	(paper "A4")
	(title_block
		(title "01162023_DA0F0TEBIF0_F0T_Expander_BD_F_brd_V02_OCP.brd")
		(comment 1 "Grand Teton / footprint 6396 of 9728 (U117), pads 1-101 of 101")
	)
	(layers
		(0 "F.Cu" signal "TOP")
		(4 "In1.Cu" signal "GND")
		(6 "In2.Cu" signal "VCC")
		(8 "In3.Cu" signal "VCC1")
		(10 "In4.Cu" signal "GND1")
		(12 "In5.Cu" signal "IN1")
		(14 "In6.Cu" signal "GND2")
		(16 "In7.Cu" signal "IN2")
		(18 "In8.Cu" signal "GND3")
		(20 "In9.Cu" signal "IN3")
		(22 "In10.Cu" signal "GND4")
		(24 "In11.Cu" signal "IN4")
		(26 "In12.Cu" signal "GND5")
		(28 "In13.Cu" signal "IN5")
		(30 "In14.Cu" signal "GND6")
		(32 "In15.Cu" signal "IN6")
		(34 "In16.Cu" signal "GND7")
		(2 "B.Cu" signal "BOTTOM")
		(9 "F.Adhes" user "F.Adhesive")
		(11 "B.Adhes" user "B.Adhesive")
		(13 "F.Paste" user "Package Geometry/Pastemask Top")
		(15 "B.Paste" user "Package Geometry/Pastemask Bottom")
		(5 "F.SilkS" user "Ref Des/Silkscreen Top")
		(7 "B.SilkS" user "Ref Des/Silkscreen Bottom")
		(1 "F.Mask" user "Board Geometry/Soldermask Top")
		(3 "B.Mask" user "Board Geometry/Soldermask Bottom")
		(17 "Dwgs.User" user "User.Drawings")
		(19 "Cmts.User" user "User.Comments")
		(21 "Eco1.User" user "User.Eco1")
		(23 "Eco2.User" user "User.Eco2")
		(25 "Edge.Cuts" user "Board Geometry/Outline")
		(27 "Margin" user)
		(31 "F.CrtYd" user "Package Geometry/Place Bound Top")
		(29 "B.CrtYd" user "Package Geometry/Place Bound Bottom")
		(35 "F.Fab" user "Ref Des/Assembly Top")
		(33 "B.Fab" user "Ref Des/Assembly Bottom")
	)
	(footprint ""
		(layer "F.Cu")
		(at 228.596952 -147.140422 90)
		(property "Reference" "U117"
			(at 4.851908 -5.381752 0)
			(unlocked yes)
			(layer "F.SilkS")
			(effects
				(font
					(size 0.7874 0.5842)
					(thickness 0.1524)
				)
				(justify left)
			)
		)
		(property "Value" ""
			(at 0 0 90)
			(layer "F.Fab")
			(effects
				(font
					(size 1.27 1.27)
				)
			)
		)
		(duplicate_pad_numbers_are_jumpers no)
		(pad "A1" smd rect
			(at -3.875024 -3.24993 180)
			(size 0.1778 0.5588)
			(layers "F.Cu" "F.Mask" "F.Paste")
			(net "FM_CK440_PEX_DEV_25M_EN")
		)
		(pad "A2" smd rect
			(at -3.875024 -2.750058 180)
			(size 0.1778 0.5588)
			(layers "F.Cu" "F.Mask" "F.Paste")
			(net "Net_9065")
		)
		(pad "A3" smd rect
			(at -3.875024 -2.249932 180)
			(size 0.1778 0.5588)
			(layers "F.Cu" "F.Mask" "F.Paste")
			(net "Net_9066")
		)
		(pad "A4" smd rect
			(at -3.875024 -1.75006 180)
			(size 0.1778 0.5588)
			(layers "F.Cu" "F.Mask" "F.Paste")
			(net "Net_9067")
		)
		(pad "A5" smd rect
			(at -3.875024 -1.249934 180)
			(size 0.1778 0.5588)
			(layers "F.Cu" "F.Mask" "F.Paste")
			(net "Net_9068")
		)
		(pad "A6" smd rect
			(at -3.875024 -0.750062 180)
			(size 0.1778 0.5588)
			(layers "F.Cu" "F.Mask" "F.Paste")
			(net "TP_CLK_CK440_PEX_PFT_OUT_DP")
		)
		(pad "A7" smd rect
			(at -3.875024 -0.249936 180)
			(size 0.1778 0.5588)
			(layers "F.Cu" "F.Mask" "F.Paste")
			(net "TP_CLK_CK440_PEX_PFT_OUT_DN")
		)
		(pad "A8" smd rect
			(at -3.875024 0.249936 180)
			(size 0.1778 0.5588)
			(layers "F.Cu" "F.Mask" "F.Paste")
			(net "TP_CK440_PEX_PFT_IN_DP")
		)
		(pad "A9" smd rect
			(at -3.875024 0.750062 180)
			(size 0.1778 0.5588)
			(layers "F.Cu" "F.Mask" "F.Paste")
			(net "TP_CK440_PEX_PFT_IN_DN")
		)
		(pad "A10" smd rect
			(at -3.875024 1.249934 180)
			(size 0.1778 0.5588)
			(layers "F.Cu" "F.Mask" "F.Paste")
			(net "SMB_CK440_PEX_CLK_SCL")
		)
		(pad "A11" smd rect
			(at -3.875024 1.75006 180)
			(size 0.1778 0.5588)
			(layers "F.Cu" "F.Mask" "F.Paste")
			(net "CLK_CK440_PEX_SMB_ADDR0")
		)
		(pad "A12" smd rect
			(at -3.875024 2.249932 180)
			(size 0.1778 0.5588)
			(layers "F.Cu" "F.Mask" "F.Paste")
			(net "P3V3_CLK_GEN_VDDXTAL_CK440_PEX")
		)
		(pad "A13" smd rect
			(at -3.875024 2.750058 180)
			(size 0.1778 0.5588)
			(layers "F.Cu" "F.Mask" "F.Paste")
			(net "XTAL_CK440_PEX_25M_XIN")
		)
		(pad "A14" smd rect
			(at -3.875024 3.24993 180)
			(size 0.1778 0.5588)
			(layers "F.Cu" "F.Mask" "F.Paste")
			(net "GND")
		)
		(pad "A15" smd rect
			(at -3.24993 3.875024 90)
			(size 0.1778 0.5588)
			(layers "F.Cu" "F.Mask" "F.Paste")
			(net "Net_9044")
		)
		(pad "A16" smd rect
			(at -2.750058 3.875024 90)
			(size 0.1778 0.5588)
			(layers "F.Cu" "F.Mask" "F.Paste")
			(net "CK440_PEX_SS_EN")
		)
		(pad "A17" smd rect
			(at -2.249932 3.875024 90)
			(size 0.1778 0.5588)
			(layers "F.Cu" "F.Mask" "F.Paste")
			(net "FM_CLK_EN_R")
		)
		(pad "A18" smd rect
			(at -1.75006 3.875024 90)
			(size 0.1778 0.5588)
			(layers "F.Cu" "F.Mask" "F.Paste")
			(net "Net_9069")
		)
		(pad "A19" smd rect
			(at -1.249934 3.875024 90)
			(size 0.1778 0.5588)
			(layers "F.Cu" "F.Mask" "F.Paste")
			(net "Net_9070")
		)
		(pad "A20" smd rect
			(at -0.750062 3.875024 90)
			(size 0.1778 0.5588)
			(layers "F.Cu" "F.Mask" "F.Paste")
			(net "Net_9071")
		)
		(pad "A21" smd rect
			(at -0.249936 3.875024 90)
			(size 0.1778 0.5588)
			(layers "F.Cu" "F.Mask" "F.Paste")
			(net "Net_9072")
		)
		(pad "A22" smd rect
			(at 0.249936 3.875024 90)
			(size 0.1778 0.5588)
			(layers "F.Cu" "F.Mask" "F.Paste")
			(net "Net_9073")
		)
		(pad "A23" smd rect
			(at 0.750062 3.875024 90)
			(size 0.1778 0.5588)
			(layers "F.Cu" "F.Mask" "F.Paste")
			(net "Net_9074")
		)
		(pad "A24" smd rect
			(at 1.249934 3.875024 90)
			(size 0.1778 0.5588)
			(layers "F.Cu" "F.Mask" "F.Paste")
			(net "CLK_100M_PEX3_REF_DN")
		)
		(pad "A25" smd rect
			(at 1.75006 3.875024 90)
			(size 0.1778 0.5588)
			(layers "F.Cu" "F.Mask" "F.Paste")
			(net "CLK_100M_PEX3_REF_DP")
		)
		(pad "A26" smd rect
			(at 2.249932 3.875024 90)
			(size 0.1778 0.5588)
			(layers "F.Cu" "F.Mask" "F.Paste")
			(net "PEX_REF_CLK_GEN_EN_N")
		)
		(pad "A27" smd rect
			(at 2.750058 3.875024 90)
			(size 0.1778 0.5588)
			(layers "F.Cu" "F.Mask" "F.Paste")
			(net "CLK_100M_PEX2_REF_DN")
		)
		(pad "A28" smd rect
			(at 3.24993 3.875024 90)
			(size 0.1778 0.5588)
			(layers "F.Cu" "F.Mask" "F.Paste")
			(net "CLK_100M_PEX2_REF_DP")
		)
		(pad "A29" smd rect
			(at 3.875024 3.24993)
			(size 0.1778 0.5588)
			(layers "F.Cu" "F.Mask" "F.Paste")
			(net "PEX_REF_CLK_GEN_EN_N")
		)
		(pad "A30" smd rect
			(at 3.875024 2.750058)
			(size 0.1778 0.5588)
			(layers "F.Cu" "F.Mask" "F.Paste")
			(net "PEX_REF_CLK_GEN_EN_N")
		)
		(pad "A31" smd rect
			(at 3.875024 2.249932)
			(size 0.1778 0.5588)
			(layers "F.Cu" "F.Mask" "F.Paste")
			(net "CLK_100M_PEX1_REF_DN")
		)
		(pad "A32" smd rect
			(at 3.875024 1.75006)
			(size 0.1778 0.5588)
			(layers "F.Cu" "F.Mask" "F.Paste")
			(net "CLK_100M_PEX1_REF_DP")
		)
		(pad "A33" smd rect
			(at 3.875024 1.249934)
			(size 0.1778 0.5588)
			(layers "F.Cu" "F.Mask" "F.Paste")
			(net "CLK_100M_PEX0_REF_DN")
		)
		(pad "A34" smd rect
			(at 3.875024 0.750062)
			(size 0.1778 0.5588)
			(layers "F.Cu" "F.Mask" "F.Paste")
			(net "CLK_100M_PEX0_REF_DP")
		)
		(pad "A35" smd rect
			(at 3.875024 0.249936)
			(size 0.1778 0.5588)
			(layers "F.Cu" "F.Mask" "F.Paste")
			(net "Net_9045")
		)
		(pad "A36" smd rect
			(at 3.875024 -0.249936)
			(size 0.1778 0.5588)
			(layers "F.Cu" "F.Mask" "F.Paste")
			(net "Net_9046")
		)
		(pad "A37" smd rect
			(at 3.875024 -0.750062)
			(size 0.1778 0.5588)
			(layers "F.Cu" "F.Mask" "F.Paste")
			(net "Net_9047")
		)
		(pad "A38" smd rect
			(at 3.875024 -1.249934)
			(size 0.1778 0.5588)
			(layers "F.Cu" "F.Mask" "F.Paste")
			(net "Net_9048")
		)
		(pad "A39" smd rect
			(at 3.875024 -1.75006)
			(size 0.1778 0.5588)
			(layers "F.Cu" "F.Mask" "F.Paste")
			(net "Net_9049")
		)
		(pad "A40" smd rect
			(at 3.875024 -2.249932)
			(size 0.1778 0.5588)
			(layers "F.Cu" "F.Mask" "F.Paste")
			(net "Net_9050")
		)
		(pad "A41" smd rect
			(at 3.875024 -2.750058)
			(size 0.1778 0.5588)
			(layers "F.Cu" "F.Mask" "F.Paste")
			(net "Net_9051")
		)
		(pad "A42" smd rect
			(at 3.875024 -3.24993)
			(size 0.1778 0.5588)
			(layers "F.Cu" "F.Mask" "F.Paste")
			(net "Net_9052")
		)
		(pad "A43" smd rect
			(at 3.24993 -3.875024 90)
			(size 0.1778 0.5588)
			(layers "F.Cu" "F.Mask" "F.Paste")
			(net "Net_9053")
		)
		(pad "A44" smd rect
			(at 2.750058 -3.875024 90)
			(size 0.1778 0.5588)
			(layers "F.Cu" "F.Mask" "F.Paste")
			(net "Net_9054")
		)
		(pad "A45" smd rect
			(at 2.249932 -3.875024 90)
			(size 0.1778 0.5588)
			(layers "F.Cu" "F.Mask" "F.Paste")
			(net "Net_9055")
		)
		(pad "A46" smd rect
			(at 1.75006 -3.875024 90)
			(size 0.1778 0.5588)
			(layers "F.Cu" "F.Mask" "F.Paste")
			(net "Net_9056")
		)
		(pad "A47" smd rect
			(at 1.249934 -3.875024 90)
			(size 0.1778 0.5588)
			(layers "F.Cu" "F.Mask" "F.Paste")
			(net "Net_9057")
		)
		(pad "A48" smd rect
			(at 0.750062 -3.875024 90)
			(size 0.1778 0.5588)
			(layers "F.Cu" "F.Mask" "F.Paste")
			(net "Net_9058")
		)
		(pad "A49" smd rect
			(at 0.249936 -3.875024 90)
			(size 0.1778 0.5588)
			(layers "F.Cu" "F.Mask" "F.Paste")
			(net "Net_9059")
		)
		(pad "A50" smd rect
			(at -0.249936 -3.875024 90)
			(size 0.1778 0.5588)
			(layers "F.Cu" "F.Mask" "F.Paste")
			(net "Net_9060")
		)
		(pad "A51" smd rect
			(at -0.750062 -3.875024 90)
			(size 0.1778 0.5588)
			(layers "F.Cu" "F.Mask" "F.Paste")
			(net "Net_9061")
		)
		(pad "A52" smd rect
			(at -1.249934 -3.875024 90)
			(size 0.1778 0.5588)
			(layers "F.Cu" "F.Mask" "F.Paste")
			(net "Net_9062")
		)
		(pad "A53" smd rect
			(at -1.75006 -3.875024 90)
			(size 0.1778 0.5588)
			(layers "F.Cu" "F.Mask" "F.Paste")
			(net "TP_CK440_PEX_SBI_DATA_OUT")
		)
		(pad "A54" smd rect
			(at -2.249932 -3.875024 90)
			(size 0.1778 0.5588)
			(layers "F.Cu" "F.Mask" "F.Paste")
			(net "PD_CK440_PEX_SBI_CLK")
		)
		(pad "A55" smd rect
			(at -2.750058 -3.875024 90)
			(size 0.1778 0.5588)
			(layers "F.Cu" "F.Mask" "F.Paste")
			(net "Net_9063")
		)
		(pad "A56" smd rect
			(at -3.24993 -3.875024 90)
			(size 0.1778 0.5588)
			(layers "F.Cu" "F.Mask" "F.Paste")
			(net "Net_9064")
		)
		(pad "B1" smd rect
			(at -3.124962 -2.500122 180)
			(size 0.2794 0.4572)
			(layers "F.Cu" "F.Mask" "F.Paste")
			(net "P3V3_CLK_GEN_VDDA25M_CK440_PEX")
		)
		(pad "B2" smd rect
			(at -3.124962 -1.999996 180)
			(size 0.2794 0.4572)
			(layers "F.Cu" "F.Mask" "F.Paste")
			(net "Net_9040")
		)
		(pad "B3" smd rect
			(at -3.124962 -1.500124 180)
			(size 0.2794 0.4572)
			(layers "F.Cu" "F.Mask" "F.Paste")
			(net "Net_9033")
		)
		(pad "B4" smd rect
			(at -3.124962 -0.999998 180)
			(size 0.2794 0.4572)
			(layers "F.Cu" "F.Mask" "F.Paste")
			(net "PU_CK440_PEX_PFT_LOST_N")
		)
		(pad "B5" smd rect
			(at -3.124962 -0.499872 180)
			(size 0.2794 0.4572)
			(layers "F.Cu" "F.Mask" "F.Paste")
			(net "Net_9023")
		)
		(pad "B6" smd rect
			(at -3.124962 0 180)
			(size 0.2794 0.4572)
			(layers "F.Cu" "F.Mask" "F.Paste")
			(net "P3V3_CLK_GEN_VDDPT_CK440_PEX")
		)
		(pad "B7" smd rect
			(at -3.124962 0.499872 180)
			(size 0.2794 0.4572)
			(layers "F.Cu" "F.Mask" "F.Paste")
			(net "Net_9022")
		)
		(pad "B8" smd rect
			(at -3.124962 0.999998 180)
			(size 0.2794 0.4572)
			(layers "F.Cu" "F.Mask" "F.Paste")
			(net "SMB_CK440_PEX_CLK_SDA")
		)
		(pad "B9" smd rect
			(at -3.124962 1.500124 180)
			(size 0.2794 0.4572)
			(layers "F.Cu" "F.Mask" "F.Paste")
			(net "CLK_CK440_PEX_SMB_ADDR1")
		)
		(pad "B10" smd rect
			(at -3.124962 1.999996 180)
			(size 0.2794 0.4572)
			(layers "F.Cu" "F.Mask" "F.Paste")
			(net "GND")
		)
		(pad "B11" smd rect
			(at -3.124962 2.500122 180)
			(size 0.2794 0.4572)
			(layers "F.Cu" "F.Mask" "F.Paste")
			(net "XTAL_CK440_PEX_25M_XOUT")
		)
		(pad "B12" smd rect
			(at -2.500122 3.124962 90)
			(size 0.2794 0.4572)
			(layers "F.Cu" "F.Mask" "F.Paste")
			(net "GND")
		)
		(pad "B13" smd rect
			(at -1.999996 3.124962 90)
			(size 0.2794 0.4572)
			(layers "F.Cu" "F.Mask" "F.Paste")
			(net "Net_9043")
		)
		(pad "B14" smd rect
			(at -1.500124 3.124962 90)
			(size 0.2794 0.4572)
			(layers "F.Cu" "F.Mask" "F.Paste")
			(net "CLK_GEN_CK440_PEX_OE6_N")
		)
		(pad "B15" smd rect
			(at -0.999998 3.124962 90)
			(size 0.2794 0.4572)
			(layers "F.Cu" "F.Mask" "F.Paste")
			(net "CLK_GEN_CK440_PEX_OE5_N")
		)
		(pad "B16" smd rect
			(at -0.499872 3.124962 90)
			(size 0.2794 0.4572)
			(layers "F.Cu" "F.Mask" "F.Paste")
			(net "Net_9042")
		)
		(pad "B17" smd rect
			(at 0 3.124962 90)
			(size 0.2794 0.4572)
			(layers "F.Cu" "F.Mask" "F.Paste")
			(net "P3V3_CLK_GEN_VDDA100M_CK440_PEX")
		)
		(pad "B18" smd rect
			(at 0.499872 3.124962 90)
			(size 0.2794 0.4572)
			(layers "F.Cu" "F.Mask" "F.Paste")
			(net "Net_9041")
		)
		(pad "B19" smd rect
			(at 0.999998 3.124962 90)
			(size 0.2794 0.4572)
			(layers "F.Cu" "F.Mask" "F.Paste")
			(net "CLK_GEN_CK440_PEX_OE4_N")
		)
		(pad "B20" smd rect
			(at 1.500124 3.124962 90)
			(size 0.2794 0.4572)
			(layers "F.Cu" "F.Mask" "F.Paste")
			(net "Net_9039")
		)
		(pad "B21" smd rect
			(at 1.999996 3.124962 90)
			(size 0.2794 0.4572)
			(layers "F.Cu" "F.Mask" "F.Paste")
			(net "P3V3_CLK_GEN_VDD_CK440_PEX")
		)
		(pad "B22" smd rect
			(at 2.500122 3.124962 90)
			(size 0.2794 0.4572)
			(layers "F.Cu" "F.Mask" "F.Paste")
			(net "Net_9038")
		)
		(pad "B23" smd rect
			(at 3.124962 2.500122)
			(size 0.2794 0.4572)
			(layers "F.Cu" "F.Mask" "F.Paste")
			(net "P3V3_CLK_GEN_VDD_CK440_PEX")
		)
		(pad "B24" smd rect
			(at 3.124962 1.999996)
			(size 0.2794 0.4572)
			(layers "F.Cu" "F.Mask" "F.Paste")
			(net "Net_9037")
		)
		(pad "B25" smd rect
			(at 3.124962 1.500124)
			(size 0.2794 0.4572)
			(layers "F.Cu" "F.Mask" "F.Paste")
			(net "Net_9036")
		)
		(pad "B26" smd rect
			(at 3.124962 0.999998)
			(size 0.2794 0.4572)
			(layers "F.Cu" "F.Mask" "F.Paste")
			(net "Net_9035")
		)
		(pad "B27" smd rect
			(at 3.124962 0.499872)
			(size 0.2794 0.4572)
			(layers "F.Cu" "F.Mask" "F.Paste")
			(net "PEX_REF_CLK_GEN_EN_N")
		)
		(pad "B28" smd rect
			(at 3.124962 0)
			(size 0.2794 0.4572)
			(layers "F.Cu" "F.Mask" "F.Paste")
			(net "Net_9034")
		)
		(pad "B29" smd rect
			(at 3.124962 -0.499872)
			(size 0.2794 0.4572)
			(layers "F.Cu" "F.Mask" "F.Paste")
			(net "P3V3_CLK_GEN_VDDMXCK_CK440_PEX")
		)
		(pad "B30" smd rect
			(at 3.124962 -0.999998)
			(size 0.2794 0.4572)
			(layers "F.Cu" "F.Mask" "F.Paste")
			(net "Net_9032")
		)
		(pad "B31" smd rect
			(at 3.124962 -1.500124)
			(size 0.2794 0.4572)
			(layers "F.Cu" "F.Mask" "F.Paste")
			(net "Net_9031")
		)
		(pad "B32" smd rect
			(at 3.124962 -1.999996)
			(size 0.2794 0.4572)
			(layers "F.Cu" "F.Mask" "F.Paste")
			(net "P3V3_CLK_GEN_VDDMXCK_CK440_PEX")
		)
		(pad "B33" smd rect
			(at 3.124962 -2.500122)
			(size 0.2794 0.4572)
			(layers "F.Cu" "F.Mask" "F.Paste")
			(net "Net_9030")
		)
		(pad "B34" smd rect
			(at 2.500122 -3.124962 90)
			(size 0.2794 0.4572)
			(layers "F.Cu" "F.Mask" "F.Paste")
			(net "Net_9029")
		)
		(pad "B35" smd rect
			(at 1.999996 -3.124962 90)
			(size 0.2794 0.4572)
			(layers "F.Cu" "F.Mask" "F.Paste")
			(net "P3V3_CLK_GEN_VDDMXCK_CK440_PEX")
		)
		(pad "B36" smd rect
			(at 1.500124 -3.124962 90)
			(size 0.2794 0.4572)
			(layers "F.Cu" "F.Mask" "F.Paste")
			(net "Net_9028")
		)
		(pad "B37" smd rect
			(at 0.999998 -3.124962 90)
			(size 0.2794 0.4572)
			(layers "F.Cu" "F.Mask" "F.Paste")
			(net "Net_9027")
		)
		(pad "B38" smd rect
			(at 0.499872 -3.124962 90)
			(size 0.2794 0.4572)
			(layers "F.Cu" "F.Mask" "F.Paste")
			(net "FM_CK440_PEX_MXCK_25M_100M")
		)
		(pad "B39" smd rect
			(at 0 -3.124962 90)
			(size 0.2794 0.4572)
			(layers "F.Cu" "F.Mask" "F.Paste")
			(net "Net_9026")
		)
		(pad "B40" smd rect
			(at -0.499872 -3.124962 90)
			(size 0.2794 0.4572)
			(layers "F.Cu" "F.Mask" "F.Paste")
			(net "P3V3_CLK_GEN_VDDMXCK_CK440_PEX")
		)
		(pad "B41" smd rect
			(at -0.999998 -3.124962 90)
			(size 0.2794 0.4572)
			(layers "F.Cu" "F.Mask" "F.Paste")
			(net "Net_9025")
		)
		(pad "B42" smd rect
			(at -1.500124 -3.124962 90)
			(size 0.2794 0.4572)
			(layers "F.Cu" "F.Mask" "F.Paste")
			(net "PU_CK440_PEX_SHFT_LD_N")
		)
		(pad "B43" smd rect
			(at -1.999996 -3.124962 90)
			(size 0.2794 0.4572)
			(layers "F.Cu" "F.Mask" "F.Paste")
			(net "PD_CK440_PEX_SBI_DATA_IN")
		)
		(pad "B44" smd rect
			(at -2.500122 -3.124962 90)
			(size 0.2794 0.4572)
			(layers "F.Cu" "F.Mask" "F.Paste")
			(net "Net_9024")
		)
		(pad "C1" smd circle
			(at 0 0 90)
			(size 0 0)
			(layers "F.Cu" "F.Mask" "F.Paste")
			(net "GND")
		)
	)
)
